(kicad_pcb
	(version 20260206)
	(generator "pcbnew")
	(generator_version "10.0")
	(general
		(thickness 1.6)
		(legacy_teardrops no)
	)
	(paper "A4")
	(title_block
		(title "01162023_DA0F0TEBIF0_F0T_Expander_BD_F_brd_V02_OCP.brd")
		(comment 1 "Grand Teton / footprints 4235-4241 of 9728")
	)
	(layers
		(0 "F.Cu" signal "TOP")
		(4 "In1.Cu" signal "GND")
		(6 "In2.Cu" signal "VCC")
		(8 "In3.Cu" signal "VCC1")
		(10 "In4.Cu" signal "GND1")
		(12 "In5.Cu" signal "IN1")
		(14 "In6.Cu" signal "GND2")
		(16 "In7.Cu" signal "IN2")
		(18 "In8.Cu" signal "GND3")
		(20 "In9.Cu" signal "IN3")
		(22 "In10.Cu" signal "GND4")
		(24 "In11.Cu" signal "IN4")
		(26 "In12.Cu" signal "GND5")
		(28 "In13.Cu" signal "IN5")
		(30 "In14.Cu" signal "GND6")
		(32 "In15.Cu" signal "IN6")
		(34 "In16.Cu" signal "GND7")
		(2 "B.Cu" signal "BOTTOM")
		(9 "F.Adhes" user "F.Adhesive")
		(11 "B.Adhes" user "B.Adhesive")
		(13 "F.Paste" user "Package Geometry/Pastemask Top")
		(15 "B.Paste" user "Package Geometry/Pastemask Bottom")
		(5 "F.SilkS" user "Ref Des/Silkscreen Top")
		(7 "B.SilkS" user "Ref Des/Silkscreen Bottom")
		(1 "F.Mask" user "Board Geometry/Soldermask Top")
		(3 "B.Mask" user "Board Geometry/Soldermask Bottom")
		(17 "Dwgs.User" user "User.Drawings")
		(19 "Cmts.User" user "User.Comments")
		(21 "Eco1.User" user "User.Eco1")
		(23 "Eco2.User" user "User.Eco2")
		(25 "Edge.Cuts" user "Board Geometry/Outline")
		(27 "Margin" user)
		(31 "F.CrtYd" user "Package Geometry/Place Bound Top")
		(29 "B.CrtYd" user "Package Geometry/Place Bound Bottom")
		(35 "F.Fab" user "Ref Des/Assembly Top")
		(33 "B.Fab" user "Ref Des/Assembly Bottom")
	)
	(footprint ""
		(layer "F.Cu")
		(at 338.074 -158.75 180)
		(property "Reference" "R4813"
			(at 0 0 180)
			(layer "F.SilkS")
			(hide yes)
			(effects
				(font
					(size 1.27 1.27)
				)
			)
		)
		(property "Value" ""
			(at 0 0 180)
			(layer "F.Fab")
			(effects
				(font
					(size 1.27 1.27)
				)
			)
		)
		(duplicate_pad_numbers_are_jumpers no)
		(fp_line
			(start 0.7874 0.4064)
			(end -0.7874 0.4064)
			(stroke
				(width 0.1524)
				(type default)
			)
			(layer "F.SilkS")
		)
		(fp_line
			(start 0.7874 -0.4064)
			(end 0.7874 0.4064)
			(stroke
				(width 0.1524)
				(type default)
			)
			(layer "F.SilkS")
		)
		(fp_line
			(start -0.7874 0.4064)
			(end -0.7874 -0.4064)
			(stroke
				(width 0.1524)
				(type default)
			)
			(layer "F.SilkS")
		)
		(fp_line
			(start -0.7874 -0.4064)
			(end 0.7874 -0.4064)
			(stroke
				(width 0.1524)
				(type default)
			)
			(layer "F.SilkS")
		)
		(fp_line
			(start 0.67945 0.3048)
			(end 0.120396 0.3048)
			(stroke
				(width 0.1)
				(type default)
			)
			(layer "F.Fab")
		)
		(fp_line
			(start 0.67945 -0.3048)
			(end 0.67945 0.3048)
			(stroke
				(width 0.1)
				(type default)
			)
			(layer "F.Fab")
		)
		(fp_line
			(start 0.12065 -0.2794)
			(end 0.12065 -0.3048)
			(stroke
				(width 0.1)
				(type default)
			)
			(layer "F.Fab")
		)
		(fp_line
			(start 0.12065 -0.3048)
			(end 0.67945 -0.3048)
			(stroke
				(width 0.1)
				(type default)
			)
			(layer "F.Fab")
		)
		(fp_line
			(start 0.120396 0.3048)
			(end 0.120396 0.2794)
			(stroke
				(width 0.1)
				(type default)
			)
			(layer "F.Fab")
		)
		(fp_line
			(start 0.120396 0.2794)
			(end -0.12065 0.2794)
			(stroke
				(width 0.1)
				(type default)
			)
			(layer "F.Fab")
		)
		(fp_line
			(start -0.12065 0.3048)
			(end -0.67945 0.3048)
			(stroke
				(width 0.1)
				(type default)
			)
			(layer "F.Fab")
		)
		(fp_line
			(start -0.12065 0.2794)
			(end -0.12065 0.3048)
			(stroke
				(width 0.1)
				(type default)
			)
			(layer "F.Fab")
		)
		(fp_line
			(start -0.12065 -0.2794)
			(end 0.12065 -0.2794)
			(stroke
				(width 0.1)
				(type default)
			)
			(layer "F.Fab")
		)
		(fp_line
			(start -0.12065 -0.305054)
			(end -0.12065 -0.2794)
			(stroke
				(width 0.1)
				(type default)
			)
			(layer "F.Fab")
		)
		(fp_line
			(start -0.67945 0.3048)
			(end -0.67945 -0.305054)
			(stroke
				(width 0.1)
				(type default)
			)
			(layer "F.Fab")
		)
		(fp_line
			(start -0.67945 -0.305054)
			(end -0.12065 -0.305054)
			(stroke
				(width 0.1)
				(type default)
			)
			(layer "F.Fab")
		)
		(pad "1" smd circle
			(at -0.40005 0 180)
			(size 0 0)
			(layers "F.Cu" "F.Mask" "F.Paste")
			(net "SSD12_PEX_PWR_EN")
		)
		(pad "2" smd circle
			(at 0.40005 0 180)
			(size 0 0)
			(layers "F.Cu" "F.Mask" "F.Paste")
			(net "SSD12_PEX_PWR_EN_R")
		)
	)
	(footprint ""
		(layer "F.Cu")
		(at 214.534496 -30.03169 180)
		(property "Reference" "C305"
			(at 0 0 180)
			(layer "F.SilkS")
			(hide yes)
			(effects
				(font
					(size 1.27 1.27)
				)
			)
		)
		(property "Value" ""
			(at 0 0 180)
			(layer "F.Fab")
			(effects
				(font
					(size 1.27 1.27)
				)
			)
		)
		(duplicate_pad_numbers_are_jumpers no)
		(fp_line
			(start 0.299974 0.150114)
			(end -0.299974 0.150114)
			(stroke
				(width 0.1)
				(type default)
			)
			(layer "F.Fab")
		)
		(fp_line
			(start 0.299974 -0.150114)
			(end 0.299974 0.150114)
			(stroke
				(width 0.1)
				(type default)
			)
			(layer "F.Fab")
		)
		(fp_line
			(start -0.299974 0.150114)
			(end -0.299974 -0.150114)
			(stroke
				(width 0.1)
				(type default)
			)
			(layer "F.Fab")
		)
		(fp_line
			(start -0.299974 -0.150114)
			(end 0.299974 -0.150114)
			(stroke
				(width 0.1)
				(type default)
			)
			(layer "F.Fab")
		)
		(pad "1" smd rect
			(at -0.2667 0 180)
			(size 0.3048 0.381)
			(layers "F.Cu" "F.Mask" "F.Paste")
			(net "P5E_PEX1_STN2_TX_DN<33>")
		)
		(pad "2" smd rect
			(at 0.2667 0 180)
			(size 0.3048 0.381)
			(layers "F.Cu" "F.Mask" "F.Paste")
			(net "P5E_PEX1_STN2_TX_C_DN<33>")
		)
	)
	(footprint ""
		(layer "F.Cu")
		(at 101.439726 -222.064072 -90)
		(property "Reference" "PR186"
			(at 0 0 270)
			(layer "F.SilkS")
			(hide yes)
			(effects
				(font
					(size 1.27 1.27)
				)
			)
		)
		(property "Value" ""
			(at 0 0 270)
			(layer "F.Fab")
			(effects
				(font
					(size 1.27 1.27)
				)
			)
		)
		(duplicate_pad_numbers_are_jumpers no)
		(fp_line
			(start -0.7874 0.4064)
			(end -0.7874 -0.4064)
			(stroke
				(width 0.1524)
				(type default)
			)
			(layer "F.SilkS")
		)
		(fp_line
			(start 0.7874 0.4064)
			(end -0.7874 0.4064)
			(stroke
				(width 0.1524)
				(type default)
			)
			(layer "F.SilkS")
		)
		(fp_line
			(start -0.7874 -0.4064)
			(end 0.7874 -0.4064)
			(stroke
				(width 0.1524)
				(type default)
			)
			(layer "F.SilkS")
		)
		(fp_line
			(start 0.7874 -0.4064)
			(end 0.7874 0.4064)
			(stroke
				(width 0.1524)
				(type default)
			)
			(layer "F.SilkS")
		)
		(fp_line
			(start -0.67945 0.3048)
			(end -0.67945 -0.305054)
			(stroke
				(width 0.1)
				(type default)
			)
			(layer "F.Fab")
		)
		(fp_line
			(start -0.12065 0.3048)
			(end -0.67945 0.3048)
			(stroke
				(width 0.1)
				(type default)
			)
			(layer "F.Fab")
		)
		(fp_line
			(start 0.120396 0.3048)
			(end 0.120396 0.2794)
			(stroke
				(width 0.1)
				(type default)
			)
			(layer "F.Fab")
		)
		(fp_line
			(start 0.67945 0.3048)
			(end 0.120396 0.3048)
			(stroke
				(width 0.1)
				(type default)
			)
			(layer "F.Fab")
		)
		(fp_line
			(start -0.12065 0.2794)
			(end -0.12065 0.3048)
			(stroke
				(width 0.1)
				(type default)
			)
			(layer "F.Fab")
		)
		(fp_line
			(start 0.120396 0.2794)
			(end -0.12065 0.2794)
			(stroke
				(width 0.1)
				(type default)
			)
			(layer "F.Fab")
		)
		(fp_line
			(start -0.12065 -0.2794)
			(end 0.12065 -0.2794)
			(stroke
				(width 0.1)
				(type default)
			)
			(layer "F.Fab")
		)
		(fp_line
			(start 0.12065 -0.2794)
			(end 0.12065 -0.3048)
			(stroke
				(width 0.1)
				(type default)
			)
			(layer "F.Fab")
		)
		(fp_line
			(start 0.12065 -0.3048)
			(end 0.67945 -0.3048)
			(stroke
				(width 0.1)
				(type default)
			)
			(layer "F.Fab")
		)
		(fp_line
			(start 0.67945 -0.3048)
			(end 0.67945 0.3048)
			(stroke
				(width 0.1)
				(type default)
			)
			(layer "F.Fab")
		)
		(fp_line
			(start -0.67945 -0.305054)
			(end -0.12065 -0.305054)
			(stroke
				(width 0.1)
				(type default)
			)
			(layer "F.Fab")
		)
		(fp_line
			(start -0.12065 -0.305054)
			(end -0.12065 -0.2794)
			(stroke
				(width 0.1)
				(type default)
			)
			(layer "F.Fab")
		)
		(pad "1" smd circle
			(at -0.40005 0 270)
			(size 0 0)
			(layers "F.Cu" "F.Mask" "F.Paste")
			(net "SH_P1V8_PEX_FB")
		)
		(pad "2" smd circle
			(at 0.40005 0 270)
			(size 0 0)
			(layers "F.Cu" "F.Mask" "F.Paste")
			(net "P1V8_PEX_FB")
		)
	)
	(footprint ""
		(layer "F.Cu")
		(at 14.708886 -251.123704 -90)
		(property "Reference" "C4244"
			(at 0 0 270)
			(layer "F.SilkS")
			(hide yes)
			(effects
				(font
					(size 1.27 1.27)
				)
			)
		)
		(property "Value" ""
			(at 0 0 270)
			(layer "F.Fab")
			(effects
				(font
					(size 1.27 1.27)
				)
			)
		)
		(duplicate_pad_numbers_are_jumpers no)
		(fp_line
			(start -1.524 0.762)
			(end -1.524 -0.762)
			(stroke
				(width 0.1524)
				(type default)
			)
			(layer "F.SilkS")
		)
		(fp_line
			(start 1.524 0.762)
			(end -1.524 0.762)
			(stroke
				(width 0.1524)
				(type default)
			)
			(layer "F.SilkS")
		)
		(fp_line
			(start -1.524 -0.762)
			(end 1.524 -0.762)
			(stroke
				(width 0.1524)
				(type default)
			)
			(layer "F.SilkS")
		)
		(fp_line
			(start 1.524 -0.762)
			(end 1.524 0.762)
			(stroke
				(width 0.1524)
				(type default)
			)
			(layer "F.SilkS")
		)
		(fp_line
			(start -1.1049 0.724916)
			(end 1.1049 0.724916)
			(stroke
				(width 0.1)
				(type default)
			)
			(layer "F.Fab")
		)
		(fp_line
			(start 1.1049 0.724916)
			(end 1.1049 -0.724916)
			(stroke
				(width 0.1)
				(type default)
			)
			(layer "F.Fab")
		)
		(fp_line
			(start -1.1049 -0.724916)
			(end -1.1049 0.724916)
			(stroke
				(width 0.1)
				(type default)
			)
			(layer "F.Fab")
		)
		(fp_line
			(start 1.1049 -0.724916)
			(end -1.1049 -0.724916)
			(stroke
				(width 0.1)
				(type default)
			)
			(layer "F.Fab")
		)
		(pad "1" smd rect
			(at -0.889 0 90)
			(size 1.016 1.27)
			(layers "F.Cu" "F.Mask" "F.Paste")
			(net "P1V25_SERDES_VDDPLL_PEX0_C10")
		)
		(pad "2" smd rect
			(at 0.889 0 90)
			(size 1.016 1.27)
			(layers "F.Cu" "F.Mask" "F.Paste")
			(net "GND")
		)
		(zone
			(layer "F.Cu")
			(hatch none 0.5)
			(connect_pads
				(clearance 0)
			)
			(min_thickness 0.25)
			(keepout
				(tracks not_allowed)
				(vias allowed)
				(pads allowed)
				(copperpour not_allowed)
				(footprints allowed)
			)
			(placement
				(enabled no)
				(sheetname "")
			)
			(fill
				(thermal_gap 0.5)
				(thermal_bridge_width 0.5)
				(island_removal_mode 0)
			)
			(polygon
				(pts
					(xy 15.433802 -251.453904) (xy 13.98397 -251.453904) (xy 13.98397 -250.793504) (xy 15.433802 -250.793504)
				)
			)
		)
	)
	(footprint ""
		(layer "F.Cu")
		(at 327.533 -220.218 180)
		(property "Reference" "R4162"
			(at 0 0 180)
			(layer "F.SilkS")
			(hide yes)
			(effects
				(font
					(size 1.27 1.27)
				)
			)
		)
		(property "Value" ""
			(at 0 0 180)
			(layer "F.Fab")
			(effects
				(font
					(size 1.27 1.27)
				)
			)
		)
		(duplicate_pad_numbers_are_jumpers no)
		(fp_line
			(start 0.7874 0.4064)
			(end -0.7874 0.4064)
			(stroke
				(width 0.1524)
				(type default)
			)
			(layer "F.SilkS")
		)
		(fp_line
			(start 0.7874 -0.4064)
			(end 0.7874 0.4064)
			(stroke
				(width 0.1524)
				(type default)
			)
			(layer "F.SilkS")
		)
		(fp_line
			(start -0.7874 0.4064)
			(end -0.7874 -0.4064)
			(stroke
				(width 0.1524)
				(type default)
			)
			(layer "F.SilkS")
		)
		(fp_line
			(start -0.7874 -0.4064)
			(end 0.7874 -0.4064)
			(stroke
				(width 0.1524)
				(type default)
			)
			(layer "F.SilkS")
		)
		(fp_line
			(start 0.67945 0.3048)
			(end 0.120396 0.3048)
			(stroke
				(width 0.1)
				(type default)
			)
			(layer "F.Fab")
		)
		(fp_line
			(start 0.67945 -0.3048)
			(end 0.67945 0.3048)
			(stroke
				(width 0.1)
				(type default)
			)
			(layer "F.Fab")
		)
		(fp_line
			(start 0.12065 -0.2794)
			(end 0.12065 -0.3048)
			(stroke
				(width 0.1)
				(type default)
			)
			(layer "F.Fab")
		)
		(fp_line
			(start 0.12065 -0.3048)
			(end 0.67945 -0.3048)
			(stroke
				(width 0.1)
				(type default)
			)
			(layer "F.Fab")
		)
		(fp_line
			(start 0.120396 0.3048)
			(end 0.120396 0.2794)
			(stroke
				(width 0.1)
				(type default)
			)
			(layer "F.Fab")
		)
		(fp_line
			(start 0.120396 0.2794)
			(end -0.12065 0.2794)
			(stroke
				(width 0.1)
				(type default)
			)
			(layer "F.Fab")
		)
		(fp_line
			(start -0.12065 0.3048)
			(end -0.67945 0.3048)
			(stroke
				(width 0.1)
				(type default)
			)
			(layer "F.Fab")
		)
		(fp_line
			(start -0.12065 0.2794)
			(end -0.12065 0.3048)
			(stroke
				(width 0.1)
				(type default)
			)
			(layer "F.Fab")
		)
		(fp_line
			(start -0.12065 -0.2794)
			(end 0.12065 -0.2794)
			(stroke
				(width 0.1)
				(type default)
			)
			(layer "F.Fab")
		)
		(fp_line
			(start -0.12065 -0.305054)
			(end -0.12065 -0.2794)
			(stroke
				(width 0.1)
				(type default)
			)
			(layer "F.Fab")
		)
		(fp_line
			(start -0.67945 0.3048)
			(end -0.67945 -0.305054)
			(stroke
				(width 0.1)
				(type default)
			)
			(layer "F.Fab")
		)
		(fp_line
			(start -0.67945 -0.305054)
			(end -0.12065 -0.305054)
			(stroke
				(width 0.1)
				(type default)
			)
			(layer "F.Fab")
		)
		(pad "1" smd circle
			(at -0.40005 0 180)
			(size 0 0)
			(layers "F.Cu" "F.Mask" "F.Paste")
			(net "PRSNT_SSD15_FPGA_N")
		)
		(pad "2" smd circle
			(at 0.40005 0 180)
			(size 0 0)
			(layers "F.Cu" "F.Mask" "F.Paste")
			(net "PRSNT_SSD15_FPGA_R_N")
		)
	)
	(footprint ""
		(layer "F.Cu")
		(at 50.481992 -38.041072 180)
		(property "Reference" "R5884"
			(at 0 0 180)
			(layer "F.SilkS")
			(hide yes)
			(effects
				(font
					(size 1.27 1.27)
				)
			)
		)
		(property "Value" ""
			(at 0 0 180)
			(layer "F.Fab")
			(effects
				(font
					(size 1.27 1.27)
				)
			)
		)
		(duplicate_pad_numbers_are_jumpers no)
		(fp_line
			(start 0.7874 0.4064)
			(end -0.7874 0.4064)
			(stroke
				(width 0.1524)
				(type default)
			)
			(layer "F.SilkS")
		)
		(fp_line
			(start 0.7874 -0.4064)
			(end 0.7874 0.4064)
			(stroke
				(width 0.1524)
				(type default)
			)
			(layer "F.SilkS")
		)
		(fp_line
			(start -0.7874 0.4064)
			(end -0.7874 -0.4064)
			(stroke
				(width 0.1524)
				(type default)
			)
			(layer "F.SilkS")
		)
		(fp_line
			(start -0.7874 -0.4064)
			(end 0.7874 -0.4064)
			(stroke
				(width 0.1524)
				(type default)
			)
			(layer "F.SilkS")
		)
		(fp_line
			(start 0.67945 0.3048)
			(end 0.120396 0.3048)
			(stroke
				(width 0.1)
				(type default)
			)
			(layer "F.Fab")
		)
		(fp_line
			(start 0.67945 -0.3048)
			(end 0.67945 0.3048)
			(stroke
				(width 0.1)
				(type default)
			)
			(layer "F.Fab")
		)
		(fp_line
			(start 0.12065 -0.2794)
			(end 0.12065 -0.3048)
			(stroke
				(width 0.1)
				(type default)
			)
			(layer "F.Fab")
		)
		(fp_line
			(start 0.12065 -0.3048)
			(end 0.67945 -0.3048)
			(stroke
				(width 0.1)
				(type default)
			)
			(layer "F.Fab")
		)
		(fp_line
			(start 0.120396 0.3048)
			(end 0.120396 0.2794)
			(stroke
				(width 0.1)
				(type default)
			)
			(layer "F.Fab")
		)
		(fp_line
			(start 0.120396 0.2794)
			(end -0.12065 0.2794)
			(stroke
				(width 0.1)
				(type default)
			)
			(layer "F.Fab")
		)
		(fp_line
			(start -0.12065 0.3048)
			(end -0.67945 0.3048)
			(stroke
				(width 0.1)
				(type default)
			)
			(layer "F.Fab")
		)
		(fp_line
			(start -0.12065 0.2794)
			(end -0.12065 0.3048)
			(stroke
				(width 0.1)
				(type default)
			)
			(layer "F.Fab")
		)
		(fp_line
			(start -0.12065 -0.2794)
			(end 0.12065 -0.2794)
			(stroke
				(width 0.1)
				(type default)
			)
			(layer "F.Fab")
		)
		(fp_line
			(start -0.12065 -0.305054)
			(end -0.12065 -0.2794)
			(stroke
				(width 0.1)
				(type default)
			)
			(layer "F.Fab")
		)
		(fp_line
			(start -0.67945 0.3048)
			(end -0.67945 -0.305054)
			(stroke
				(width 0.1)
				(type default)
			)
			(layer "F.Fab")
		)
		(fp_line
			(start -0.67945 -0.305054)
			(end -0.12065 -0.305054)
			(stroke
				(width 0.1)
				(type default)
			)
			(layer "F.Fab")
		)
		(pad "1" smd circle
			(at -0.40005 0 180)
			(size 0 0)
			(layers "F.Cu" "F.Mask" "F.Paste")
			(net "P5V_AUX")
		)
		(pad "2" smd circle
			(at 0.40005 0 180)
			(size 0 0)
			(layers "F.Cu" "F.Mask" "F.Paste")
			(net "P3V3_SSD2_PG_G2")
		)
	)
	(footprint ""
		(layer "F.Cu")
		(at 276.726396 -414.88995 -90)
		(property "Reference" "R1817"
			(at 0 0 270)
			(layer "F.SilkS")
			(hide yes)
			(effects
				(font
					(size 1.27 1.27)
				)
			)
		)
		(property "Value" ""
			(at 0 0 270)
			(layer "F.Fab")
			(effects
				(font
					(size 1.27 1.27)
				)
			)
		)
		(duplicate_pad_numbers_are_jumpers no)
		(fp_line
			(start -0.7874 0.4064)
			(end -0.7874 -0.4064)
			(stroke
				(width 0.1524)
				(type default)
			)
			(layer "F.SilkS")
		)
		(fp_line
			(start 0.7874 0.4064)
			(end -0.7874 0.4064)
			(stroke
				(width 0.1524)
				(type default)
			)
			(layer "F.SilkS")
		)
		(fp_line
			(start -0.7874 -0.4064)
			(end 0.7874 -0.4064)
			(stroke
				(width 0.1524)
				(type default)
			)
			(layer "F.SilkS")
		)
		(fp_line
			(start 0.7874 -0.4064)
			(end 0.7874 0.4064)
			(stroke
				(width 0.1524)
				(type default)
			)
			(layer "F.SilkS")
		)
		(fp_line
			(start -0.67945 0.3048)
			(end -0.67945 -0.305054)
			(stroke
				(width 0.1)
				(type default)
			)
			(layer "F.Fab")
		)
		(fp_line
			(start -0.12065 0.3048)
			(end -0.67945 0.3048)
			(stroke
				(width 0.1)
				(type default)
			)
			(layer "F.Fab")
		)
		(fp_line
			(start 0.120396 0.3048)
			(end 0.120396 0.2794)
			(stroke
				(width 0.1)
				(type default)
			)
			(layer "F.Fab")
		)
		(fp_line
			(start 0.67945 0.3048)
			(end 0.120396 0.3048)
			(stroke
				(width 0.1)
				(type default)
			)
			(layer "F.Fab")
		)
		(fp_line
			(start -0.12065 0.2794)
			(end -0.12065 0.3048)
			(stroke
				(width 0.1)
				(type default)
			)
			(layer "F.Fab")
		)
		(fp_line
			(start 0.120396 0.2794)
			(end -0.12065 0.2794)
			(stroke
				(width 0.1)
				(type default)
			)
			(layer "F.Fab")
		)
		(fp_line
			(start -0.12065 -0.2794)
			(end 0.12065 -0.2794)
			(stroke
				(width 0.1)
				(type default)
			)
			(layer "F.Fab")
		)
		(fp_line
			(start 0.12065 -0.2794)
			(end 0.12065 -0.3048)
			(stroke
				(width 0.1)
				(type default)
			)
			(layer "F.Fab")
		)
		(fp_line
			(start 0.12065 -0.3048)
			(end 0.67945 -0.3048)
			(stroke
				(width 0.1)
				(type default)
			)
			(layer "F.Fab")
		)
		(fp_line
			(start 0.67945 -0.3048)
			(end 0.67945 0.3048)
			(stroke
				(width 0.1)
				(type default)
			)
			(layer "F.Fab")
		)
		(fp_line
			(start -0.67945 -0.305054)
			(end -0.12065 -0.305054)
			(stroke
				(width 0.1)
				(type default)
			)
			(layer "F.Fab")
		)
		(fp_line
			(start -0.12065 -0.305054)
			(end -0.12065 -0.2794)
			(stroke
				(width 0.1)
				(type default)
			)
			(layer "F.Fab")
		)
		(pad "1" smd circle
			(at -0.40005 0 270)
			(size 0 0)
			(layers "F.Cu" "F.Mask" "F.Paste")
			(net "RST_MB_BMC_N")
		)
		(pad "2" smd circle
			(at 0.40005 0 270)
			(size 0 0)
			(layers "F.Cu" "F.Mask" "F.Paste")
			(net "RST_MB_BMC_R_N")
		)
	)
)
